# BASEBOARD_FAB2 (Tioga Pass) — schematic netlist excerpt (pin names and nets, part order shuffled) for the footprints in the layout excerpt that follows; sources: Cadence DE-HDL packaged netlist, KiCad conversion of Wiwynn_Tioga_Pass_MB.brd

R8W13  RES  0.0 5% CHIP  pkg 0402  page 245 : A = JTAG_RISER_TDI_R ; B = JTAG_RISER_TDI
C5A19  CAP_A  47UF 4V 20% X5R  pkg 0603V  page 220 : A = PVDDQ_DEF ; B = GND
C5D30  CAP_A  22.0UF 4V 20% X6S  pkg 0603V  page 42 : A = PVCCIN_CPU0 ; B = GND

(kicad_pcb
	(version 20260206)
	(generator "pcbnew")
	(generator_version "10.0")
	(general
		(thickness 1.6)
		(legacy_teardrops no)
	)
	(paper "A4")
	(title_block
		(title "Wiwynn_Tioga_Pass_MB.brd")
		(comment 1 "Tioga Pass / footprints 1908-1910 of 4770")
	)
	(layers
		(0 "F.Cu" signal "TOP")
		(4 "In1.Cu" signal "L2GND")
		(6 "In2.Cu" signal "L3")
		(8 "In3.Cu" signal "L4GND")
		(10 "In4.Cu" signal "L5")
		(12 "In5.Cu" signal "L6GND")
		(14 "In6.Cu" signal "L7VCC")
		(16 "In7.Cu" signal "L8VCC")
		(18 "In8.Cu" signal "L9GND")
		(20 "In9.Cu" signal "L10")
		(22 "In10.Cu" signal "L11GND")
		(24 "In11.Cu" signal "L12")
		(26 "In12.Cu" signal "L13GND")
		(2 "B.Cu" signal "BOTTOM")
		(9 "F.Adhes" user "F.Adhesive")
		(11 "B.Adhes" user "B.Adhesive")
		(13 "F.Paste" user "Package Geometry/Pastemask Top")
		(15 "B.Paste" user "Package Geometry/Pastemask Bottom")
		(5 "F.SilkS" user "Ref Des/Silkscreen Top")
		(7 "B.SilkS" user "Ref Des/Silkscreen Bottom")
		(1 "F.Mask" user "Board Geometry/Soldermask Top")
		(3 "B.Mask" user "Board Geometry/Soldermask Bottom")
		(17 "Dwgs.User" user "User.Drawings")
		(19 "Cmts.User" user "User.Comments")
		(21 "Eco1.User" user "User.Eco1")
		(23 "Eco2.User" user "User.Eco2")
		(25 "Edge.Cuts" user "Board Geometry/Outline")
		(27 "Margin" user)
		(31 "F.CrtYd" user "Package Geometry/Place Bound Top")
		(29 "B.CrtYd" user "Package Geometry/Place Bound Bottom")
		(35 "F.Fab" user "Ref Des/Assembly Top")
		(33 "B.Fab" user "Ref Des/Assembly Bottom")
	)
	(footprint ""
		(layer "F.Cu")
		(at 360.765598 -10.916158)
		(property "Reference" "R8W13"
			(at -0.8382 -0.67818 0)
			(unlocked yes)
			(layer "F.SilkS")
			(effects
				(font
					(size 0.4064 0.254)
					(thickness 0.1524)
				)
				(justify left)
			)
		)
		(property "Value" ""
			(at 0 0 0)
			(layer "F.Fab")
			(effects
				(font
					(size 1.27 1.27)
				)
			)
		)
		(duplicate_pad_numbers_are_jumpers no)
		(fp_poly
			(pts
				(xy -0.2794 -0.1016) (xy 0.2794 -0.1016) (xy 0.2794 0.9906) (xy -0.2794 0.9906)
			)
			(stroke
				(width 0)
				(type default)
			)
			(fill no)
			(layer "F.CrtYd")
		)
		(fp_line
			(start -0.2794 -0.1016)
			(end -0.2794 0.9906)
			(stroke
				(width 0.1)
				(type default)
			)
			(layer "F.Fab")
		)
		(fp_line
			(start -0.2794 0.9906)
			(end 0.2794 0.9906)
			(stroke
				(width 0.1)
				(type default)
			)
			(layer "F.Fab")
		)
		(fp_line
			(start 0.2794 -0.1016)
			(end -0.2794 -0.1016)
			(stroke
				(width 0.1)
				(type default)
			)
			(layer "F.Fab")
		)
		(fp_line
			(start 0.2794 0.9906)
			(end 0.2794 -0.1016)
			(stroke
				(width 0.1)
				(type default)
			)
			(layer "F.Fab")
		)
		(pad "1" smd rect
			(at 0 0)
			(size 0.508 0.508)
			(layers "F.Cu" "F.Mask" "F.Paste")
			(net "JTAG_RISER_TDI_R")
		)
		(pad "2" smd rect
			(at 0 0.889)
			(size 0.508 0.508)
			(layers "F.Cu" "F.Mask" "F.Paste")
			(net "JTAG_RISER_TDI")
		)
		(zone
			(layer "F.Cu")
			(hatch none 0.5)
			(connect_pads
				(clearance 0)
			)
			(min_thickness 0.25)
			(keepout
				(tracks allowed)
				(vias not_allowed)
				(pads allowed)
				(copperpour not_allowed)
				(footprints allowed)
			)
			(placement
				(enabled no)
				(sheetname "")
			)
			(fill
				(thermal_gap 0.5)
				(thermal_bridge_width 0.5)
				(island_removal_mode 0)
			)
			(polygon
				(pts
					(xy 360.511598 -10.662158) (xy 361.019598 -10.662158) (xy 361.019598 -10.281158) (xy 360.511598 -10.281158)
				)
			)
		)
		(zone
			(layer "F.Cu")
			(hatch none 0.5)
			(connect_pads
				(clearance 0)
			)
			(min_thickness 0.25)
			(keepout
				(tracks not_allowed)
				(vias allowed)
				(pads allowed)
				(copperpour not_allowed)
				(footprints allowed)
			)
			(placement
				(enabled no)
				(sheetname "")
			)
			(fill
				(thermal_gap 0.5)
				(thermal_bridge_width 0.5)
				(island_removal_mode 0)
			)
			(polygon
				(pts
					(xy 360.511598 -10.281158) (xy 361.019598 -10.281158) (xy 361.019598 -10.662158) (xy 360.511598 -10.662158)
				)
			)
		)
	)
	(footprint ""
		(layer "F.Cu")
		(at 276.000464 -140.208 90)
		(property "Reference" "C5A19"
			(at 1.848866 0.752348 90)
			(unlocked yes)
			(layer "F.SilkS")
			(effects
				(font
					(size 1.27 0.9652)
					(thickness 0.1524)
				)
			)
		)
		(property "Value" ""
			(at 0 0 90)
			(layer "F.Fab")
			(effects
				(font
					(size 1.27 1.27)
				)
			)
		)
		(duplicate_pad_numbers_are_jumpers no)
		(fp_rect
			(start -0.500126 1.598422)
			(end 0.500126 -0.201422)
			(stroke
				(width 0)
				(type default)
			)
			(fill no)
			(layer "F.CrtYd")
		)
		(fp_line
			(start 0.500126 -0.201422)
			(end 0.500126 1.598422)
			(stroke
				(width 0.1)
				(type default)
			)
			(layer "F.Fab")
		)
		(fp_line
			(start -0.500126 -0.201422)
			(end 0.500126 -0.201422)
			(stroke
				(width 0.1)
				(type default)
			)
			(layer "F.Fab")
		)
		(fp_line
			(start 0.500126 1.598422)
			(end -0.500126 1.598422)
			(stroke
				(width 0.1)
				(type default)
			)
			(layer "F.Fab")
		)
		(fp_line
			(start -0.500126 1.598422)
			(end -0.500126 -0.201422)
			(stroke
				(width 0.1)
				(type default)
			)
			(layer "F.Fab")
		)
		(pad "1" smd rect
			(at 0 0)
			(size 0.889 0.9906)
			(layers "F.Cu" "F.Mask" "F.Paste")
			(net "PVDDQ_DEF")
		)
		(pad "2" smd rect
			(at 0 1.397)
			(size 0.889 0.9906)
			(layers "F.Cu" "F.Mask" "F.Paste")
			(net "GND")
		)
		(zone
			(layer "F.Cu")
			(hatch none 0.5)
			(connect_pads
				(clearance 0)
			)
			(min_thickness 0.25)
			(keepout
				(tracks allowed)
				(vias not_allowed)
				(pads allowed)
				(copperpour not_allowed)
				(footprints allowed)
			)
			(placement
				(enabled no)
				(sheetname "")
			)
			(fill
				(thermal_gap 0.5)
				(thermal_bridge_width 0.5)
				(island_removal_mode 0)
			)
			(polygon
				(pts
					(xy 276.952964 -139.7127) (xy 276.952964 -140.7033) (xy 276.444964 -140.7033) (xy 276.444964 -139.7127)
				)
			)
		)
		(zone
			(layer "F.Cu")
			(hatch none 0.5)
			(connect_pads
				(clearance 0)
			)
			(min_thickness 0.25)
			(keepout
				(tracks not_allowed)
				(vias allowed)
				(pads allowed)
				(copperpour not_allowed)
				(footprints allowed)
			)
			(placement
				(enabled no)
				(sheetname "")
			)
			(fill
				(thermal_gap 0.5)
				(thermal_bridge_width 0.5)
				(island_removal_mode 0)
			)
			(polygon
				(pts
					(xy 276.952964 -139.7127) (xy 276.952964 -140.7033) (xy 276.444964 -140.7033) (xy 276.444964 -139.7127)
				)
			)
		)
	)
	(footprint ""
		(layer "F.Cu")
		(at 265.675872 -77.636116)
		(property "Reference" "C5D30"
			(at 0 0 0)
			(layer "F.SilkS")
			(hide yes)
			(effects
				(font
					(size 1.27 1.27)
				)
			)
		)
		(property "Value" ""
			(at 0 0 0)
			(layer "F.Fab")
			(effects
				(font
					(size 1.27 1.27)
				)
			)
		)
		(duplicate_pad_numbers_are_jumpers no)
		(fp_poly
			(pts
				(xy -0.4953 -0.2032) (xy 0.4953 -0.2032) (xy 0.4953 1.6002) (xy -0.4953 1.6002)
			)
			(stroke
				(width 0)
				(type default)
			)
			(fill no)
			(layer "F.CrtYd")
		)
		(fp_line
			(start -0.4953 -0.2032)
			(end 0.4953 -0.2032)
			(stroke
				(width 0.1)
				(type default)
			)
			(layer "F.Fab")
		)
		(fp_line
			(start -0.4953 1.6002)
			(end -0.4953 -0.2032)
			(stroke
				(width 0.1)
				(type default)
			)
			(layer "F.Fab")
		)
		(fp_line
			(start 0.4953 -0.2032)
			(end 0.4953 1.6002)
			(stroke
				(width 0.1)
				(type default)
			)
			(layer "F.Fab")
		)
		(fp_line
			(start 0.4953 1.6002)
			(end -0.4953 1.6002)
			(stroke
				(width 0.1)
				(type default)
			)
			(layer "F.Fab")
		)
		(pad "1" smd rect
			(at 0 0)
			(size 0.762 0.889)
			(layers "F.Cu" "F.Mask" "F.Paste")
			(net "PVCCIN_CPU0")
		)
		(pad "2" smd rect
			(at 0 1.397)
			(size 0.762 0.889)
			(layers "F.Cu" "F.Mask" "F.Paste")
			(net "GND")
		)
		(zone
			(layer "F.Cu")
			(hatch none 0.5)
			(connect_pads
				(clearance 0)
			)
			(min_thickness 0.25)
			(keepout
				(tracks not_allowed)
				(vias allowed)
				(pads allowed)
				(copperpour not_allowed)
				(footprints allowed)
			)
			(placement
				(enabled no)
				(sheetname "")
			)
			(fill
				(thermal_gap 0.5)
				(thermal_bridge_width 0.5)
				(island_removal_mode 0)
			)
			(polygon
				(pts
					(xy 265.294872 -77.191616) (xy 266.056872 -77.191616) (xy 266.056872 -76.683616) (xy 265.294872 -76.683616)
				)
			)
		)
	)
)
